# T6G (Grand Teton) — schematic netlist excerpt (pin names and nets, part order shuffled) for the footprints in the layout excerpt that follows; sources: Cadence DE-HDL packaged netlist, KiCad conversion of 04192023_DAF0TMB3IC0_F0TG_MB_C_brd_V02_OCP.brd

PC132_5  Q_CAP  0.1UF 25V 10% X7R  pkg 0402  page 203 : A = PVDDCR_CPU1_P0_VCCS ; B = GND
C795  Q_CAP  100UF 4V 20% X6S  pkg C0805  page 301 : A = P0V9_CPU0_RT2_2A ; B = GND
PC507_11P1_1  Q_CAP  2.2UF 10V 10% X6S  pkg C0402  page 225 : A = PVDD11_S3_P1_PVCC ; B = GND

(kicad_pcb
	(version 20260206)
	(generator "pcbnew")
	(generator_version "10.0")
	(general
		(thickness 1.6)
		(legacy_teardrops no)
	)
	(paper "A4")
	(title_block
		(title "04192023_DAF0TMB3IC0_F0TG_MB_C_brd_V02_OCP.brd")
		(comment 1 "Grand Teton / footprints 436-438 of 8354")
	)
	(layers
		(0 "F.Cu" signal "TOP")
		(4 "In1.Cu" signal "GND")
		(6 "In2.Cu" signal "IN1")
		(8 "In3.Cu" signal "GND1")
		(10 "In4.Cu" signal "IN2")
		(12 "In5.Cu" signal "GND2")
		(14 "In6.Cu" signal "IN3")
		(16 "In7.Cu" signal "GND3")
		(18 "In8.Cu" signal "VCC")
		(20 "In9.Cu" signal "VCC1")
		(22 "In10.Cu" signal "GND4")
		(24 "In11.Cu" signal "IN4")
		(26 "In12.Cu" signal "GND5")
		(28 "In13.Cu" signal "IN5")
		(30 "In14.Cu" signal "GND6")
		(32 "In15.Cu" signal "IN6")
		(34 "In16.Cu" signal "GND7")
		(2 "B.Cu" signal "BOTTOM")
		(9 "F.Adhes" user "F.Adhesive")
		(11 "B.Adhes" user "B.Adhesive")
		(13 "F.Paste" user "Package Geometry/Pastemask Top")
		(15 "B.Paste" user "Package Geometry/Pastemask Bottom")
		(5 "F.SilkS" user "Ref Des/Silkscreen Top")
		(7 "B.SilkS" user "Ref Des/Silkscreen Bottom")
		(1 "F.Mask" user "Board Geometry/Soldermask Top")
		(3 "B.Mask" user "Board Geometry/Soldermask Bottom")
		(17 "Dwgs.User" user "User.Drawings")
		(19 "Cmts.User" user "User.Comments")
		(21 "Eco1.User" user "User.Eco1")
		(23 "Eco2.User" user "User.Eco2")
		(25 "Edge.Cuts" user "Board Geometry/Outline")
		(27 "Margin" user)
		(31 "F.CrtYd" user "Package Geometry/Place Bound Top")
		(29 "B.CrtYd" user "Package Geometry/Place Bound Bottom")
		(35 "F.Fab" user "Ref Des/Assembly Top")
		(33 "B.Fab" user "Ref Des/Assembly Bottom")
	)
	(footprint ""
		(layer "F.Cu")
		(at 426.213778 -400.456146)
		(property "Reference" "C795"
			(at 0 0 0)
			(layer "F.SilkS")
			(hide yes)
			(effects
				(font
					(size 1.27 1.27)
				)
			)
		)
		(property "Value" ""
			(at 0 0 0)
			(layer "F.Fab")
			(effects
				(font
					(size 1.27 1.27)
				)
			)
		)
		(duplicate_pad_numbers_are_jumpers no)
		(fp_line
			(start -1.524 -0.762)
			(end 1.524 -0.762)
			(stroke
				(width 0.1524)
				(type default)
			)
			(layer "F.SilkS")
		)
		(fp_line
			(start -1.524 0.762)
			(end -1.524 -0.762)
			(stroke
				(width 0.1524)
				(type default)
			)
			(layer "F.SilkS")
		)
		(fp_line
			(start 1.524 -0.762)
			(end 1.524 0.762)
			(stroke
				(width 0.1524)
				(type default)
			)
			(layer "F.SilkS")
		)
		(fp_line
			(start 1.524 0.762)
			(end -1.524 0.762)
			(stroke
				(width 0.1524)
				(type default)
			)
			(layer "F.SilkS")
		)
		(fp_line
			(start -1.1049 -0.724916)
			(end -1.1049 0.724916)
			(stroke
				(width 0.1)
				(type default)
			)
			(layer "F.Fab")
		)
		(fp_line
			(start -1.1049 0.724916)
			(end 1.1049 0.724916)
			(stroke
				(width 0.1)
				(type default)
			)
			(layer "F.Fab")
		)
		(fp_line
			(start 1.1049 -0.724916)
			(end -1.1049 -0.724916)
			(stroke
				(width 0.1)
				(type default)
			)
			(layer "F.Fab")
		)
		(fp_line
			(start 1.1049 0.724916)
			(end 1.1049 -0.724916)
			(stroke
				(width 0.1)
				(type default)
			)
			(layer "F.Fab")
		)
		(pad "1" smd rect
			(at -0.889 0 180)
			(size 1.016 1.27)
			(layers "F.Cu" "F.Mask" "F.Paste")
			(net "P0V9_CPU0_RT2_2A")
		)
		(pad "2" smd rect
			(at 0.889 0 180)
			(size 1.016 1.27)
			(layers "F.Cu" "F.Mask" "F.Paste")
			(net "GND")
		)
	)
	(footprint ""
		(layer "F.Cu")
		(at 340.696296 -339.881972 90)
		(property "Reference" "PC132_5"
			(at 0 0 90)
			(layer "F.SilkS")
			(hide yes)
			(effects
				(font
					(size 1.27 1.27)
				)
			)
		)
		(property "Value" ""
			(at 0 0 90)
			(layer "F.Fab")
			(effects
				(font
					(size 1.27 1.27)
				)
			)
		)
		(duplicate_pad_numbers_are_jumpers no)
		(fp_line
			(start 0.7874 -0.4064)
			(end 0.7874 0.4064)
			(stroke
				(width 0.1524)
				(type default)
			)
			(layer "F.SilkS")
		)
		(fp_line
			(start -0.7874 -0.4064)
			(end 0.7874 -0.4064)
			(stroke
				(width 0.1524)
				(type default)
			)
			(layer "F.SilkS")
		)
		(fp_line
			(start 0.7874 0.4064)
			(end -0.7874 0.4064)
			(stroke
				(width 0.1524)
				(type default)
			)
			(layer "F.SilkS")
		)
		(fp_line
			(start -0.7874 0.4064)
			(end -0.7874 -0.4064)
			(stroke
				(width 0.1524)
				(type default)
			)
			(layer "F.SilkS")
		)
		(fp_line
			(start -0.12065 -0.305054)
			(end -0.12065 -0.2794)
			(stroke
				(width 0.1)
				(type default)
			)
			(layer "F.Fab")
		)
		(fp_line
			(start -0.67945 -0.305054)
			(end -0.12065 -0.305054)
			(stroke
				(width 0.1)
				(type default)
			)
			(layer "F.Fab")
		)
		(fp_line
			(start 0.67945 -0.3048)
			(end 0.67945 0.3048)
			(stroke
				(width 0.1)
				(type default)
			)
			(layer "F.Fab")
		)
		(fp_line
			(start 0.12065 -0.3048)
			(end 0.67945 -0.3048)
			(stroke
				(width 0.1)
				(type default)
			)
			(layer "F.Fab")
		)
		(fp_line
			(start 0.12065 -0.2794)
			(end 0.12065 -0.3048)
			(stroke
				(width 0.1)
				(type default)
			)
			(layer "F.Fab")
		)
		(fp_line
			(start -0.12065 -0.2794)
			(end 0.12065 -0.2794)
			(stroke
				(width 0.1)
				(type default)
			)
			(layer "F.Fab")
		)
		(fp_line
			(start 0.120396 0.2794)
			(end -0.12065 0.2794)
			(stroke
				(width 0.1)
				(type default)
			)
			(layer "F.Fab")
		)
		(fp_line
			(start -0.12065 0.2794)
			(end -0.12065 0.3048)
			(stroke
				(width 0.1)
				(type default)
			)
			(layer "F.Fab")
		)
		(fp_line
			(start 0.67945 0.3048)
			(end 0.120396 0.3048)
			(stroke
				(width 0.1)
				(type default)
			)
			(layer "F.Fab")
		)
		(fp_line
			(start 0.120396 0.3048)
			(end 0.120396 0.2794)
			(stroke
				(width 0.1)
				(type default)
			)
			(layer "F.Fab")
		)
		(fp_line
			(start -0.12065 0.3048)
			(end -0.67945 0.3048)
			(stroke
				(width 0.1)
				(type default)
			)
			(layer "F.Fab")
		)
		(fp_line
			(start -0.67945 0.3048)
			(end -0.67945 -0.305054)
			(stroke
				(width 0.1)
				(type default)
			)
			(layer "F.Fab")
		)
		(pad "1" smd circle
			(at -0.40005 0 90)
			(size 0 0)
			(layers "F.Cu" "F.Mask" "F.Paste")
			(net "PVDDCR_CPU1_P0_VCCS")
		)
		(pad "2" smd circle
			(at 0.40005 0 90)
			(size 0 0)
			(layers "F.Cu" "F.Mask" "F.Paste")
			(net "GND")
		)
	)
	(footprint ""
		(layer "F.Cu")
		(at 179.236878 -351.293684 -90)
		(property "Reference" "PC507_11P1_1"
			(at 0 0 270)
			(layer "F.SilkS")
			(hide yes)
			(effects
				(font
					(size 1.27 1.27)
				)
			)
		)
		(property "Value" ""
			(at 0 0 270)
			(layer "F.Fab")
			(effects
				(font
					(size 1.27 1.27)
				)
			)
		)
		(duplicate_pad_numbers_are_jumpers no)
		(fp_line
			(start -0.7874 0.4064)
			(end -0.7874 -0.4064)
			(stroke
				(width 0.1524)
				(type default)
			)
			(layer "F.SilkS")
		)
		(fp_line
			(start 0.7874 0.4064)
			(end -0.7874 0.4064)
			(stroke
				(width 0.1524)
				(type default)
			)
			(layer "F.SilkS")
		)
		(fp_line
			(start -0.7874 -0.4064)
			(end 0.7874 -0.4064)
			(stroke
				(width 0.1524)
				(type default)
			)
			(layer "F.SilkS")
		)
		(fp_line
			(start 0.7874 -0.4064)
			(end 0.7874 0.4064)
			(stroke
				(width 0.1524)
				(type default)
			)
			(layer "F.SilkS")
		)
		(fp_line
			(start -0.67945 0.3048)
			(end -0.67945 -0.305054)
			(stroke
				(width 0.1)
				(type default)
			)
			(layer "F.Fab")
		)
		(fp_line
			(start -0.12065 0.3048)
			(end -0.67945 0.3048)
			(stroke
				(width 0.1)
				(type default)
			)
			(layer "F.Fab")
		)
		(fp_line
			(start 0.120396 0.3048)
			(end 0.120396 0.2794)
			(stroke
				(width 0.1)
				(type default)
			)
			(layer "F.Fab")
		)
		(fp_line
			(start 0.67945 0.3048)
			(end 0.120396 0.3048)
			(stroke
				(width 0.1)
				(type default)
			)
			(layer "F.Fab")
		)
		(fp_line
			(start -0.12065 0.2794)
			(end -0.12065 0.3048)
			(stroke
				(width 0.1)
				(type default)
			)
			(layer "F.Fab")
		)
		(fp_line
			(start 0.120396 0.2794)
			(end -0.12065 0.2794)
			(stroke
				(width 0.1)
				(type default)
			)
			(layer "F.Fab")
		)
		(fp_line
			(start -0.12065 -0.2794)
			(end 0.12065 -0.2794)
			(stroke
				(width 0.1)
				(type default)
			)
			(layer "F.Fab")
		)
		(fp_line
			(start 0.12065 -0.2794)
			(end 0.12065 -0.3048)
			(stroke
				(width 0.1)
				(type default)
			)
			(layer "F.Fab")
		)
		(fp_line
			(start 0.12065 -0.3048)
			(end 0.67945 -0.3048)
			(stroke
				(width 0.1)
				(type default)
			)
			(layer "F.Fab")
		)
		(fp_line
			(start 0.67945 -0.3048)
			(end 0.67945 0.3048)
			(stroke
				(width 0.1)
				(type default)
			)
			(layer "F.Fab")
		)
		(fp_line
			(start -0.67945 -0.305054)
			(end -0.12065 -0.305054)
			(stroke
				(width 0.1)
				(type default)
			)
			(layer "F.Fab")
		)
		(fp_line
			(start -0.12065 -0.305054)
			(end -0.12065 -0.2794)
			(stroke
				(width 0.1)
				(type default)
			)
			(layer "F.Fab")
		)
		(pad "1" smd circle
			(at -0.40005 0 270)
			(size 0 0)
			(layers "F.Cu" "F.Mask" "F.Paste")
			(net "PVDD11_S3_P1_PVCC")
		)
		(pad "2" smd circle
			(at 0.40005 0 270)
			(size 0 0)
			(layers "F.Cu" "F.Mask" "F.Paste")
			(net "GND")
		)
	)
)
